(kicad_pcb
	(version 20260206)
	(generator "pcbnew")
	(generator_version "10.0")
	(general
		(thickness 1.6)
		(legacy_teardrops no)
	)
	(paper "A4")
	(title_block
		(title "03242023_DA0F0TMBIJ0_F0T_Motherboard_J_brd_V01_OCP.brd")
		(comment 1 "Grand Teton / footprints 1230-1235 of 6105")
	)
	(layers
		(0 "F.Cu" signal "TOP")
		(4 "In1.Cu" signal "GND")
		(6 "In2.Cu" signal "IN1")
		(8 "In3.Cu" signal "GND1")
		(10 "In4.Cu" signal "IN2")
		(12 "In5.Cu" signal "GND2")
		(14 "In6.Cu" signal "IN3")
		(16 "In7.Cu" signal "GND3")
		(18 "In8.Cu" signal "VCC")
		(20 "In9.Cu" signal "VCC1")
		(22 "In10.Cu" signal "GND4")
		(24 "In11.Cu" signal "IN4")
		(26 "In12.Cu" signal "GND5")
		(28 "In13.Cu" signal "IN5")
		(30 "In14.Cu" signal "GND6")
		(32 "In15.Cu" signal "IN6")
		(34 "In16.Cu" signal "GND7")
		(2 "B.Cu" signal "BOTTOM")
		(9 "F.Adhes" user "F.Adhesive")
		(11 "B.Adhes" user "B.Adhesive")
		(13 "F.Paste" user "Package Geometry/Pastemask Top")
		(15 "B.Paste" user "Package Geometry/Pastemask Bottom")
		(5 "F.SilkS" user "Ref Des/Silkscreen Top")
		(7 "B.SilkS" user "Ref Des/Silkscreen Bottom")
		(1 "F.Mask" user "Board Geometry/Soldermask Top")
		(3 "B.Mask" user "Board Geometry/Soldermask Bottom")
		(17 "Dwgs.User" user "User.Drawings")
		(19 "Cmts.User" user "User.Comments")
		(21 "Eco1.User" user "User.Eco1")
		(23 "Eco2.User" user "User.Eco2")
		(25 "Edge.Cuts" user "Board Geometry/Outline")
		(27 "Margin" user)
		(31 "F.CrtYd" user "Package Geometry/Place Bound Top")
		(29 "B.CrtYd" user "Package Geometry/Place Bound Bottom")
		(35 "F.Fab" user "Ref Des/Assembly Top")
		(33 "B.Fab" user "Ref Des/Assembly Bottom")
	)
	(footprint ""
		(layer "F.Cu")
		(at 89.122758 -408.517344 -90)
		(property "Reference" "C682"
			(at 0 0 270)
			(layer "F.SilkS")
			(hide yes)
			(effects
				(font
					(size 1.27 1.27)
				)
			)
		)
		(property "Value" ""
			(at 0 0 270)
			(layer "F.Fab")
			(effects
				(font
					(size 1.27 1.27)
				)
			)
		)
		(duplicate_pad_numbers_are_jumpers no)
		(fp_line
			(start -0.299974 0.150114)
			(end -0.299974 -0.150114)
			(stroke
				(width 0.1)
				(type default)
			)
			(layer "F.Fab")
		)
		(fp_line
			(start 0.299974 0.150114)
			(end -0.299974 0.150114)
			(stroke
				(width 0.1)
				(type default)
			)
			(layer "F.Fab")
		)
		(fp_line
			(start -0.299974 -0.150114)
			(end 0.299974 -0.150114)
			(stroke
				(width 0.1)
				(type default)
			)
			(layer "F.Fab")
		)
		(fp_line
			(start 0.299974 -0.150114)
			(end 0.299974 0.150114)
			(stroke
				(width 0.1)
				(type default)
			)
			(layer "F.Fab")
		)
		(pad "1" smd rect
			(at -0.2667 0 270)
			(size 0.3048 0.381)
			(layers "F.Cu" "F.Mask" "F.Paste")
			(net "P5E_CPU1_PE4_TX_C_DN<13>")
		)
		(pad "2" smd rect
			(at 0.2667 0 270)
			(size 0.3048 0.381)
			(layers "F.Cu" "F.Mask" "F.Paste")
			(net "P5E_CPU1_PE4_TX_DN<13>")
		)
	)
	(footprint ""
		(layer "F.Cu")
		(at 327.657968 -408.517344 -90)
		(property "Reference" "C917"
			(at 0 0 270)
			(layer "F.SilkS")
			(hide yes)
			(effects
				(font
					(size 1.27 1.27)
				)
			)
		)
		(property "Value" ""
			(at 0 0 270)
			(layer "F.Fab")
			(effects
				(font
					(size 1.27 1.27)
				)
			)
		)
		(duplicate_pad_numbers_are_jumpers no)
		(fp_line
			(start -0.299974 0.150114)
			(end -0.299974 -0.150114)
			(stroke
				(width 0.1)
				(type default)
			)
			(layer "F.Fab")
		)
		(fp_line
			(start 0.299974 0.150114)
			(end -0.299974 0.150114)
			(stroke
				(width 0.1)
				(type default)
			)
			(layer "F.Fab")
		)
		(fp_line
			(start -0.299974 -0.150114)
			(end 0.299974 -0.150114)
			(stroke
				(width 0.1)
				(type default)
			)
			(layer "F.Fab")
		)
		(fp_line
			(start 0.299974 -0.150114)
			(end 0.299974 0.150114)
			(stroke
				(width 0.1)
				(type default)
			)
			(layer "F.Fab")
		)
		(pad "1" smd rect
			(at -0.2667 0 270)
			(size 0.3048 0.381)
			(layers "F.Cu" "F.Mask" "F.Paste")
			(net "P5E_CPU0_PE0_TX_C_DP<8>")
		)
		(pad "2" smd rect
			(at 0.2667 0 270)
			(size 0.3048 0.381)
			(layers "F.Cu" "F.Mask" "F.Paste")
			(net "P5E_CPU0_PE0_TX_DP<8>")
		)
	)
	(footprint ""
		(layer "F.Cu")
		(at 385.637532 -71.362824 180)
		(property "Reference" "C2287"
			(at 0 0 180)
			(layer "F.SilkS")
			(hide yes)
			(effects
				(font
					(size 1.27 1.27)
				)
			)
		)
		(property "Value" ""
			(at 0 0 180)
			(layer "F.Fab")
			(effects
				(font
					(size 1.27 1.27)
				)
			)
		)
		(duplicate_pad_numbers_are_jumpers no)
		(fp_line
			(start 0.7874 0.4064)
			(end -0.7874 0.4064)
			(stroke
				(width 0.1524)
				(type default)
			)
			(layer "F.SilkS")
		)
		(fp_line
			(start 0.7874 -0.4064)
			(end 0.7874 0.4064)
			(stroke
				(width 0.1524)
				(type default)
			)
			(layer "F.SilkS")
		)
		(fp_line
			(start -0.7874 0.4064)
			(end -0.7874 -0.4064)
			(stroke
				(width 0.1524)
				(type default)
			)
			(layer "F.SilkS")
		)
		(fp_line
			(start -0.7874 -0.4064)
			(end 0.7874 -0.4064)
			(stroke
				(width 0.1524)
				(type default)
			)
			(layer "F.SilkS")
		)
		(fp_line
			(start 0.67945 0.3048)
			(end 0.120396 0.3048)
			(stroke
				(width 0.1)
				(type default)
			)
			(layer "F.Fab")
		)
		(fp_line
			(start 0.67945 -0.3048)
			(end 0.67945 0.3048)
			(stroke
				(width 0.1)
				(type default)
			)
			(layer "F.Fab")
		)
		(fp_line
			(start 0.12065 -0.2794)
			(end 0.12065 -0.3048)
			(stroke
				(width 0.1)
				(type default)
			)
			(layer "F.Fab")
		)
		(fp_line
			(start 0.12065 -0.3048)
			(end 0.67945 -0.3048)
			(stroke
				(width 0.1)
				(type default)
			)
			(layer "F.Fab")
		)
		(fp_line
			(start 0.120396 0.3048)
			(end 0.120396 0.2794)
			(stroke
				(width 0.1)
				(type default)
			)
			(layer "F.Fab")
		)
		(fp_line
			(start 0.120396 0.2794)
			(end -0.12065 0.2794)
			(stroke
				(width 0.1)
				(type default)
			)
			(layer "F.Fab")
		)
		(fp_line
			(start -0.12065 0.3048)
			(end -0.67945 0.3048)
			(stroke
				(width 0.1)
				(type default)
			)
			(layer "F.Fab")
		)
		(fp_line
			(start -0.12065 0.2794)
			(end -0.12065 0.3048)
			(stroke
				(width 0.1)
				(type default)
			)
			(layer "F.Fab")
		)
		(fp_line
			(start -0.12065 -0.2794)
			(end 0.12065 -0.2794)
			(stroke
				(width 0.1)
				(type default)
			)
			(layer "F.Fab")
		)
		(fp_line
			(start -0.12065 -0.305054)
			(end -0.12065 -0.2794)
			(stroke
				(width 0.1)
				(type default)
			)
			(layer "F.Fab")
		)
		(fp_line
			(start -0.67945 0.3048)
			(end -0.67945 -0.305054)
			(stroke
				(width 0.1)
				(type default)
			)
			(layer "F.Fab")
		)
		(fp_line
			(start -0.67945 -0.305054)
			(end -0.12065 -0.305054)
			(stroke
				(width 0.1)
				(type default)
			)
			(layer "F.Fab")
		)
		(pad "1" smd circle
			(at -0.40005 0 180)
			(size 0 0)
			(layers "F.Cu" "F.Mask" "F.Paste")
			(net "PWRGD_P1V8_PCH_AUX")
		)
		(pad "2" smd circle
			(at 0.40005 0 180)
			(size 0 0)
			(layers "F.Cu" "F.Mask" "F.Paste")
			(net "GND")
		)
	)
	(footprint ""
		(layer "F.Cu")
		(at 185.22188 -130.266948 -90)
		(property "Reference" "R272"
			(at 0 0 270)
			(layer "F.SilkS")
			(hide yes)
			(effects
				(font
					(size 1.27 1.27)
				)
			)
		)
		(property "Value" ""
			(at 0 0 270)
			(layer "F.Fab")
			(effects
				(font
					(size 1.27 1.27)
				)
			)
		)
		(duplicate_pad_numbers_are_jumpers no)
		(fp_line
			(start -0.7874 0.4064)
			(end -0.7874 -0.4064)
			(stroke
				(width 0.1524)
				(type default)
			)
			(layer "F.SilkS")
		)
		(fp_line
			(start 0.7874 0.4064)
			(end -0.7874 0.4064)
			(stroke
				(width 0.1524)
				(type default)
			)
			(layer "F.SilkS")
		)
		(fp_line
			(start -0.7874 -0.4064)
			(end 0.7874 -0.4064)
			(stroke
				(width 0.1524)
				(type default)
			)
			(layer "F.SilkS")
		)
		(fp_line
			(start 0.7874 -0.4064)
			(end 0.7874 0.4064)
			(stroke
				(width 0.1524)
				(type default)
			)
			(layer "F.SilkS")
		)
		(fp_line
			(start -0.67945 0.3048)
			(end -0.67945 -0.305054)
			(stroke
				(width 0.1)
				(type default)
			)
			(layer "F.Fab")
		)
		(fp_line
			(start -0.12065 0.3048)
			(end -0.67945 0.3048)
			(stroke
				(width 0.1)
				(type default)
			)
			(layer "F.Fab")
		)
		(fp_line
			(start 0.120396 0.3048)
			(end 0.120396 0.2794)
			(stroke
				(width 0.1)
				(type default)
			)
			(layer "F.Fab")
		)
		(fp_line
			(start 0.67945 0.3048)
			(end 0.120396 0.3048)
			(stroke
				(width 0.1)
				(type default)
			)
			(layer "F.Fab")
		)
		(fp_line
			(start -0.12065 0.2794)
			(end -0.12065 0.3048)
			(stroke
				(width 0.1)
				(type default)
			)
			(layer "F.Fab")
		)
		(fp_line
			(start 0.120396 0.2794)
			(end -0.12065 0.2794)
			(stroke
				(width 0.1)
				(type default)
			)
			(layer "F.Fab")
		)
		(fp_line
			(start -0.12065 -0.2794)
			(end 0.12065 -0.2794)
			(stroke
				(width 0.1)
				(type default)
			)
			(layer "F.Fab")
		)
		(fp_line
			(start 0.12065 -0.2794)
			(end 0.12065 -0.3048)
			(stroke
				(width 0.1)
				(type default)
			)
			(layer "F.Fab")
		)
		(fp_line
			(start 0.12065 -0.3048)
			(end 0.67945 -0.3048)
			(stroke
				(width 0.1)
				(type default)
			)
			(layer "F.Fab")
		)
		(fp_line
			(start 0.67945 -0.3048)
			(end 0.67945 0.3048)
			(stroke
				(width 0.1)
				(type default)
			)
			(layer "F.Fab")
		)
		(fp_line
			(start -0.67945 -0.305054)
			(end -0.12065 -0.305054)
			(stroke
				(width 0.1)
				(type default)
			)
			(layer "F.Fab")
		)
		(fp_line
			(start -0.12065 -0.305054)
			(end -0.12065 -0.2794)
			(stroke
				(width 0.1)
				(type default)
			)
			(layer "F.Fab")
		)
		(pad "1" smd circle
			(at -0.40005 0 270)
			(size 0 0)
			(layers "F.Cu" "F.Mask" "F.Paste")
			(net "P3V3_AUX")
		)
		(pad "2" smd circle
			(at 0.40005 0 270)
			(size 0 0)
			(layers "F.Cu" "F.Mask" "F.Paste")
			(net "FM_CPU1_PKGID2")
		)
	)
	(footprint ""
		(layer "F.Cu")
		(at 146.12874 -33.157668)
		(property "Reference" "U244"
			(at 0.11684 1.95961 0)
			(unlocked yes)
			(layer "F.SilkS")
			(effects
				(font
					(size 0.7874 0.5842)
					(thickness 0.1524)
				)
			)
		)
		(property "Value" ""
			(at 0 0 0)
			(layer "F.Fab")
			(effects
				(font
					(size 1.27 1.27)
				)
			)
		)
		(duplicate_pad_numbers_are_jumpers no)
		(fp_line
			(start -1.7272 1.1176)
			(end -1.7272 -1.1176)
			(stroke
				(width 0.1524)
				(type default)
			)
			(layer "F.SilkS")
		)
		(fp_line
			(start -0.254 -1.1176)
			(end -1.7272 -1.1176)
			(stroke
				(width 0.1524)
				(type default)
			)
			(layer "F.SilkS")
		)
		(fp_line
			(start 0 -0.7366)
			(end -0.254 -1.1176)
			(stroke
				(width 0.1524)
				(type default)
			)
			(layer "F.SilkS")
		)
		(fp_line
			(start 0.254 -1.1176)
			(end 0 -0.7366)
			(stroke
				(width 0.1524)
				(type default)
			)
			(layer "F.SilkS")
		)
		(fp_line
			(start 1.7272 -1.1176)
			(end 0.254 -1.1176)
			(stroke
				(width 0.1524)
				(type default)
			)
			(layer "F.SilkS")
		)
		(fp_line
			(start 1.7272 -1.1176)
			(end 1.7272 1.1176)
			(stroke
				(width 0.1524)
				(type default)
			)
			(layer "F.SilkS")
		)
		(fp_line
			(start 1.7272 1.1176)
			(end -1.7272 1.1176)
			(stroke
				(width 0.1524)
				(type default)
			)
			(layer "F.SilkS")
		)
		(fp_poly
			(pts
				(xy -1.633474 -2.05994) (xy -0.871474 -2.05994) (xy -1.252474 -1.29794)
			)
			(stroke
				(width 0)
				(type default)
			)
			(fill yes)
			(layer "F.SilkS")
		)
		(fp_line
			(start -1.5748 -1.1176)
			(end -1.5748 1.1176)
			(stroke
				(width 0.1)
				(type default)
			)
			(layer "F.Fab")
		)
		(fp_line
			(start -1.5748 1.1176)
			(end 1.5748 1.1176)
			(stroke
				(width 0.1)
				(type default)
			)
			(layer "F.Fab")
		)
		(fp_line
			(start 1.5748 -1.1176)
			(end -1.5748 -1.1176)
			(stroke
				(width 0.1)
				(type default)
			)
			(layer "F.Fab")
		)
		(fp_line
			(start 1.5748 1.1176)
			(end 1.5748 -1.1176)
			(stroke
				(width 0.1)
				(type default)
			)
			(layer "F.Fab")
		)
		(fp_poly
			(pts
				(xy -1.9558 -0.649986) (xy -2.7178 -0.268986) (xy -2.7178 -1.030986)
			)
			(stroke
				(width 0)
				(type default)
			)
			(fill yes)
			(layer "F.Fab")
		)
		(pad "1" smd rect
			(at -0.999998 -0.649986 270)
			(size 0.3556 1.1176)
			(layers "F.Cu" "F.Mask" "F.Paste")
			(net "OCP_SFF_NOT_PRSNT_RBT_ARB_IN")
		)
		(pad "2" smd rect
			(at -0.999998 0 270)
			(size 0.3556 1.1176)
			(layers "F.Cu" "F.Mask" "F.Paste")
			(net "GND")
		)
		(pad "3" smd rect
			(at -0.999998 0.649986 270)
			(size 0.3556 1.1176)
			(layers "F.Cu" "F.Mask" "F.Paste")
			(net "OCP_SFF_RBT_ARB_IN")
		)
		(pad "4" smd rect
			(at 0.999998 0.649986 270)
			(size 0.3556 1.1176)
			(layers "F.Cu" "F.Mask" "F.Paste")
			(net "OCP_SFF_RBT_ARB_IN_MUX1_R")
		)
		(pad "5" smd rect
			(at 0.999998 0 270)
			(size 0.3556 1.1176)
			(layers "F.Cu" "F.Mask" "F.Paste")
			(net "P3V3_AUX")
		)
		(pad "6" smd rect
			(at 0.999998 -0.649986 270)
			(size 0.3556 1.1176)
			(layers "F.Cu" "F.Mask" "F.Paste")
			(net "OCP_SFF_PRSNT_ALL_R3_N")
		)
	)
	(footprint ""
		(layer "F.Cu")
		(at 305.58994 -430.6697 -90)
		(property "Reference" "R4136"
			(at 0 0 270)
			(layer "F.SilkS")
			(hide yes)
			(effects
				(font
					(size 1.27 1.27)
				)
			)
		)
		(property "Value" ""
			(at 0 0 270)
			(layer "F.Fab")
			(effects
				(font
					(size 1.27 1.27)
				)
			)
		)
		(duplicate_pad_numbers_are_jumpers no)
		(fp_line
			(start -0.7874 0.4064)
			(end -0.7874 -0.4064)
			(stroke
				(width 0.1524)
				(type default)
			)
			(layer "F.SilkS")
		)
		(fp_line
			(start 0.7874 0.4064)
			(end -0.7874 0.4064)
			(stroke
				(width 0.1524)
				(type default)
			)
			(layer "F.SilkS")
		)
		(fp_line
			(start -0.7874 -0.4064)
			(end 0.7874 -0.4064)
			(stroke
				(width 0.1524)
				(type default)
			)
			(layer "F.SilkS")
		)
		(fp_line
			(start 0.7874 -0.4064)
			(end 0.7874 0.4064)
			(stroke
				(width 0.1524)
				(type default)
			)
			(layer "F.SilkS")
		)
		(fp_line
			(start -0.67945 0.3048)
			(end -0.67945 -0.305054)
			(stroke
				(width 0.1)
				(type default)
			)
			(layer "F.Fab")
		)
		(fp_line
			(start -0.12065 0.3048)
			(end -0.67945 0.3048)
			(stroke
				(width 0.1)
				(type default)
			)
			(layer "F.Fab")
		)
		(fp_line
			(start 0.120396 0.3048)
			(end 0.120396 0.2794)
			(stroke
				(width 0.1)
				(type default)
			)
			(layer "F.Fab")
		)
		(fp_line
			(start 0.67945 0.3048)
			(end 0.120396 0.3048)
			(stroke
				(width 0.1)
				(type default)
			)
			(layer "F.Fab")
		)
		(fp_line
			(start -0.12065 0.2794)
			(end -0.12065 0.3048)
			(stroke
				(width 0.1)
				(type default)
			)
			(layer "F.Fab")
		)
		(fp_line
			(start 0.120396 0.2794)
			(end -0.12065 0.2794)
			(stroke
				(width 0.1)
				(type default)
			)
			(layer "F.Fab")
		)
		(fp_line
			(start -0.12065 -0.2794)
			(end 0.12065 -0.2794)
			(stroke
				(width 0.1)
				(type default)
			)
			(layer "F.Fab")
		)
		(fp_line
			(start 0.12065 -0.2794)
			(end 0.12065 -0.3048)
			(stroke
				(width 0.1)
				(type default)
			)
			(layer "F.Fab")
		)
		(fp_line
			(start 0.12065 -0.3048)
			(end 0.67945 -0.3048)
			(stroke
				(width 0.1)
				(type default)
			)
			(layer "F.Fab")
		)
		(fp_line
			(start 0.67945 -0.3048)
			(end 0.67945 0.3048)
			(stroke
				(width 0.1)
				(type default)
			)
			(layer "F.Fab")
		)
		(fp_line
			(start -0.67945 -0.305054)
			(end -0.12065 -0.305054)
			(stroke
				(width 0.1)
				(type default)
			)
			(layer "F.Fab")
		)
		(fp_line
			(start -0.12065 -0.305054)
			(end -0.12065 -0.2794)
			(stroke
				(width 0.1)
				(type default)
			)
			(layer "F.Fab")
		)
		(pad "1" smd circle
			(at -0.40005 0 270)
			(size 0 0)
			(layers "F.Cu" "F.Mask" "F.Paste")
			(net "PRSNT_CABLE_GPU_A2_N")
		)
		(pad "2" smd circle
			(at 0.40005 0 270)
			(size 0 0)
			(layers "F.Cu" "F.Mask" "F.Paste")
			(net "GND")
		)
	)
)
